(kicad_pcb
	(version 20260206)
	(generator "pcbnew")
	(generator_version "10.0")
	(general
		(thickness 1.6)
		(legacy_teardrops no)
	)
	(paper "A4")
	(title_block
		(title "Wiwynn_Tioga_Pass_MB.brd")
		(comment 1 "Tioga Pass / footprints 742-747 of 4770")
	)
	(layers
		(0 "F.Cu" signal "TOP")
		(4 "In1.Cu" signal "L2GND")
		(6 "In2.Cu" signal "L3")
		(8 "In3.Cu" signal "L4GND")
		(10 "In4.Cu" signal "L5")
		(12 "In5.Cu" signal "L6GND")
		(14 "In6.Cu" signal "L7VCC")
		(16 "In7.Cu" signal "L8VCC")
		(18 "In8.Cu" signal "L9GND")
		(20 "In9.Cu" signal "L10")
		(22 "In10.Cu" signal "L11GND")
		(24 "In11.Cu" signal "L12")
		(26 "In12.Cu" signal "L13GND")
		(2 "B.Cu" signal "BOTTOM")
		(9 "F.Adhes" user "F.Adhesive")
		(11 "B.Adhes" user "B.Adhesive")
		(13 "F.Paste" user "Package Geometry/Pastemask Top")
		(15 "B.Paste" user "Package Geometry/Pastemask Bottom")
		(5 "F.SilkS" user "Ref Des/Silkscreen Top")
		(7 "B.SilkS" user "Ref Des/Silkscreen Bottom")
		(1 "F.Mask" user "Board Geometry/Soldermask Top")
		(3 "B.Mask" user "Board Geometry/Soldermask Bottom")
		(17 "Dwgs.User" user "User.Drawings")
		(19 "Cmts.User" user "User.Comments")
		(21 "Eco1.User" user "User.Eco1")
		(23 "Eco2.User" user "User.Eco2")
		(25 "Edge.Cuts" user "Board Geometry/Outline")
		(27 "Margin" user)
		(31 "F.CrtYd" user "Package Geometry/Place Bound Top")
		(29 "B.CrtYd" user "Package Geometry/Place Bound Bottom")
		(35 "F.Fab" user "Ref Des/Assembly Top")
		(33 "B.Fab" user "Ref Des/Assembly Bottom")
	)
	(footprint ""
		(layer "F.Cu")
		(at 355.666548 -22.035516 -90)
		(property "Reference" "L7F2"
			(at 0 0 270)
			(layer "F.SilkS")
			(hide yes)
			(effects
				(font
					(size 1.27 1.27)
				)
			)
		)
		(property "Value" "*"
			(at -3.5941 0.3429 270)
			(unlocked yes)
			(layer "F.Fab")
			(hide yes)
			(effects
				(font
					(size 1.27 1.016)
					(thickness 0.1524)
				)
			)
		)
		(property "Device Type" "IND-100NH-35-GP_DISCRET-G8-INDA"
			(at -3.5941 -1.1811 270)
			(unlocked yes)
			(layer "F.Fab")
			(hide yes)
			(effects
				(font
					(size 1.27 1.016)
					(thickness 0.1524)
				)
			)
		)
		(duplicate_pad_numbers_are_jumpers no)
		(fp_line
			(start -2.2479 2.794)
			(end -2.2479 -2.794)
			(stroke
				(width 0.1524)
				(type default)
			)
			(layer "F.SilkS")
		)
		(fp_line
			(start 2.2479 2.794)
			(end -2.2479 2.794)
			(stroke
				(width 0.1524)
				(type default)
			)
			(layer "F.SilkS")
		)
		(fp_line
			(start -2.2479 -2.794)
			(end 2.2479 -2.794)
			(stroke
				(width 0.1524)
				(type default)
			)
			(layer "F.SilkS")
		)
		(fp_line
			(start 2.2479 -2.794)
			(end 2.2479 2.794)
			(stroke
				(width 0.1524)
				(type default)
			)
			(layer "F.SilkS")
		)
		(fp_rect
			(start -1.9939 1.9939)
			(end 1.9939 -1.9939)
			(stroke
				(width 0)
				(type default)
			)
			(fill no)
			(layer "F.CrtYd")
		)
		(fp_poly
			(pts
				(xy -2.5019 2.8702) (xy -2.5019 1.9939) (xy 1.9939 1.9939) (xy 1.9939 -1.9939) (xy -1.9939 -1.9939)
				(xy -1.9939 1.9812) (xy -2.5019 1.9812) (xy -2.5019 -2.8702) (xy 2.5019 -2.8702) (xy 2.5019 2.8702)
			)
			(stroke
				(width 0)
				(type default)
			)
			(fill no)
			(layer "F.CrtYd")
		)
		(fp_rect
			(start -2.5019 2.8702)
			(end 2.5019 -2.8702)
			(stroke
				(width 0)
				(type default)
			)
			(fill no)
			(layer "F.Fab")
		)
		(pad "1" smd rect
			(at 0 -1.745996 270)
			(size 1.5494 1.6002)
			(layers "F.Cu" "F.Mask" "F.Paste")
			(net "P12V_STBY")
		)
		(pad "2" smd rect
			(at 0 1.745996 270)
			(size 1.5494 1.6002)
			(layers "F.Cu" "F.Mask" "F.Paste")
			(net "VR_FET_SW_P12V_STBY_PVDDQ_ABC")
		)
	)
	(footprint ""
		(layer "F.Cu")
		(at 13.8938 -33.02 90)
		(property "Reference" "C1F6"
			(at 0 0 90)
			(layer "F.SilkS")
			(hide yes)
			(effects
				(font
					(size 1.27 1.27)
				)
			)
		)
		(property "Value" ""
			(at 0 0 90)
			(layer "F.Fab")
			(effects
				(font
					(size 1.27 1.27)
				)
			)
		)
		(duplicate_pad_numbers_are_jumpers no)
		(fp_rect
			(start -0.3048 -0.1016)
			(end 0.3048 0.9906)
			(stroke
				(width 0)
				(type default)
			)
			(fill no)
			(layer "F.CrtYd")
		)
		(fp_line
			(start 0.3048 -0.1016)
			(end -0.3048 -0.1016)
			(stroke
				(width 0.1)
				(type default)
			)
			(layer "F.Fab")
		)
		(fp_line
			(start -0.3048 -0.1016)
			(end -0.3048 0.9906)
			(stroke
				(width 0.1)
				(type default)
			)
			(layer "F.Fab")
		)
		(fp_line
			(start 0.3048 0.9906)
			(end 0.3048 -0.1016)
			(stroke
				(width 0.1)
				(type default)
			)
			(layer "F.Fab")
		)
		(fp_line
			(start -0.3048 0.9906)
			(end 0.3048 0.9906)
			(stroke
				(width 0.1)
				(type default)
			)
			(layer "F.Fab")
		)
		(pad "1" smd rect
			(at 0 0 90)
			(size 0.508 0.508)
			(layers "F.Cu" "F.Mask" "F.Paste")
			(net "P3E_CPU1_PE3_MP_C_TXP<5>")
		)
		(pad "2" smd rect
			(at 0 0.889 90)
			(size 0.508 0.508)
			(layers "F.Cu" "F.Mask" "F.Paste")
			(net "P3E_CPU1_PE3_MP_TXP<5>")
		)
		(zone
			(layer "F.Cu")
			(hatch none 0.5)
			(connect_pads
				(clearance 0)
			)
			(min_thickness 0.25)
			(keepout
				(tracks not_allowed)
				(vias allowed)
				(pads allowed)
				(copperpour not_allowed)
				(footprints allowed)
			)
			(placement
				(enabled no)
				(sheetname "")
			)
			(fill
				(thermal_gap 0.5)
				(thermal_bridge_width 0.5)
				(island_removal_mode 0)
			)
			(polygon
				(pts
					(xy 14.1478 -32.766) (xy 14.5288 -32.766) (xy 14.5288 -33.274) (xy 14.1478 -33.274)
				)
			)
		)
		(zone
			(layer "F.Cu")
			(hatch none 0.5)
			(connect_pads
				(clearance 0)
			)
			(min_thickness 0.25)
			(keepout
				(tracks allowed)
				(vias not_allowed)
				(pads allowed)
				(copperpour not_allowed)
				(footprints allowed)
			)
			(placement
				(enabled no)
				(sheetname "")
			)
			(fill
				(thermal_gap 0.5)
				(thermal_bridge_width 0.5)
				(island_removal_mode 0)
			)
			(polygon
				(pts
					(xy 14.1478 -32.766) (xy 14.5288 -32.766) (xy 14.5288 -33.274) (xy 14.1478 -33.274)
				)
			)
		)
	)
	(footprint ""
		(layer "F.Cu")
		(at 407.7335 -22.987 90)
		(property "Reference" "R25W80"
			(at -0.8382 -0.67818 90)
			(unlocked yes)
			(layer "F.SilkS")
			(effects
				(font
					(size 0.4064 0.254)
					(thickness 0.1524)
				)
				(justify left)
			)
		)
		(property "Value" ""
			(at 0 0 90)
			(layer "F.Fab")
			(effects
				(font
					(size 1.27 1.27)
				)
			)
		)
		(duplicate_pad_numbers_are_jumpers no)
		(fp_poly
			(pts
				(xy -0.2794 -0.1016) (xy 0.2794 -0.1016) (xy 0.2794 0.9906) (xy -0.2794 0.9906)
			)
			(stroke
				(width 0)
				(type default)
			)
			(fill no)
			(layer "F.CrtYd")
		)
		(fp_line
			(start 0.2794 -0.1016)
			(end -0.2794 -0.1016)
			(stroke
				(width 0.1)
				(type default)
			)
			(layer "F.Fab")
		)
		(fp_line
			(start -0.2794 -0.1016)
			(end -0.2794 0.9906)
			(stroke
				(width 0.1)
				(type default)
			)
			(layer "F.Fab")
		)
		(fp_line
			(start 0.2794 0.9906)
			(end 0.2794 -0.1016)
			(stroke
				(width 0.1)
				(type default)
			)
			(layer "F.Fab")
		)
		(fp_line
			(start -0.2794 0.9906)
			(end 0.2794 0.9906)
			(stroke
				(width 0.1)
				(type default)
			)
			(layer "F.Fab")
		)
		(pad "1" smd rect
			(at 0 0 90)
			(size 0.508 0.508)
			(layers "F.Cu" "F.Mask" "F.Paste")
			(net "P3V3_STBY")
		)
		(pad "2" smd rect
			(at 0 0.889 90)
			(size 0.508 0.508)
			(layers "F.Cu" "F.Mask" "F.Paste")
			(net "RMII_SPRNGVLLE_BMC_PCH_RXD1")
		)
		(zone
			(layer "F.Cu")
			(hatch none 0.5)
			(connect_pads
				(clearance 0)
			)
			(min_thickness 0.25)
			(keepout
				(tracks allowed)
				(vias not_allowed)
				(pads allowed)
				(copperpour not_allowed)
				(footprints allowed)
			)
			(placement
				(enabled no)
				(sheetname "")
			)
			(fill
				(thermal_gap 0.5)
				(thermal_bridge_width 0.5)
				(island_removal_mode 0)
			)
			(polygon
				(pts
					(xy 407.9875 -22.733) (xy 407.9875 -23.241) (xy 408.3685 -23.241) (xy 408.3685 -22.733)
				)
			)
		)
		(zone
			(layer "F.Cu")
			(hatch none 0.5)
			(connect_pads
				(clearance 0)
			)
			(min_thickness 0.25)
			(keepout
				(tracks not_allowed)
				(vias allowed)
				(pads allowed)
				(copperpour not_allowed)
				(footprints allowed)
			)
			(placement
				(enabled no)
				(sheetname "")
			)
			(fill
				(thermal_gap 0.5)
				(thermal_bridge_width 0.5)
				(island_removal_mode 0)
			)
			(polygon
				(pts
					(xy 408.3685 -22.733) (xy 408.3685 -23.241) (xy 407.9875 -23.241) (xy 407.9875 -22.733)
				)
			)
		)
	)
	(footprint ""
		(layer "F.Cu")
		(at 449.69938 -33.5915 90)
		(property "Reference" "R25W11"
			(at 0 0 90)
			(layer "F.SilkS")
			(hide yes)
			(effects
				(font
					(size 1.27 1.27)
				)
			)
		)
		(property "Value" "*"
			(at 0.064008 -4.108196 90)
			(unlocked yes)
			(layer "F.Fab")
			(hide yes)
			(effects
				(font
					(size 1.27 1.016)
					(thickness 0.1524)
				)
			)
		)
		(property "Device Type" "120R2F-GP_RCL_GP-120R2F-GP,64.A"
			(at 0.064008 -5.632196 90)
			(unlocked yes)
			(layer "F.Fab")
			(hide yes)
			(effects
				(font
					(size 1.27 1.016)
					(thickness 0.1524)
				)
			)
		)
		(duplicate_pad_numbers_are_jumpers no)
		(fp_line
			(start 0.508 -0.9398)
			(end -0.508 -0.9398)
			(stroke
				(width 0.1524)
				(type default)
			)
			(layer "F.SilkS")
		)
		(fp_line
			(start -0.508 -0.9398)
			(end -0.508 0.9398)
			(stroke
				(width 0.1524)
				(type default)
			)
			(layer "F.SilkS")
		)
		(fp_rect
			(start -0.508 0.9398)
			(end 0.508 -0.9398)
			(stroke
				(width 0)
				(type default)
			)
			(fill no)
			(layer "F.CrtYd")
		)
		(fp_rect
			(start -0.508 0.9398)
			(end 0.508 -0.9398)
			(stroke
				(width 0)
				(type default)
			)
			(fill no)
			(layer "F.Fab")
		)
		(pad "1" smd custom
			(at 0 -0.4445 90)
			(size 0.1397 0.1397)
			(layers "F.Cu" "F.Mask" "F.Paste")
			(net "GND")
			(options
				(clearance outline)
				(anchor circle)
			)
			(primitives
				(gr_poly
					(pts
						(arc
							(start -0.1778 -0.2794)
							(mid -0.249642 -0.249642)
							(end -0.2794 -0.1778)
						)
						(arc
							(start -0.2794 0.1778)
							(mid -0.249642 0.249642)
							(end -0.1778 0.2794)
						)
						(arc
							(start 0.1778 0.2794)
							(mid 0.249642 0.249642)
							(end 0.2794 0.1778)
						)
						(arc
							(start 0.2794 -0.1778)
							(mid 0.249642 -0.249642)
							(end 0.1778 -0.2794)
						)
					)
					(width 0)
					(fill yes)
				)
			)
		)
		(pad "2" smd custom
			(at 0 0.4445 90)
			(size 0.1397 0.1397)
			(layers "F.Cu" "F.Mask" "F.Paste")
			(net "BMC_M_BG0")
			(options
				(clearance outline)
				(anchor circle)
			)
			(primitives
				(gr_poly
					(pts
						(arc
							(start -0.1778 -0.2794)
							(mid -0.249642 -0.249642)
							(end -0.2794 -0.1778)
						)
						(arc
							(start -0.2794 0.1778)
							(mid -0.249642 0.249642)
							(end -0.1778 0.2794)
						)
						(arc
							(start 0.1778 0.2794)
							(mid 0.249642 0.249642)
							(end 0.2794 0.1778)
						)
						(arc
							(start 0.2794 -0.1778)
							(mid 0.249642 -0.249642)
							(end 0.1778 -0.2794)
						)
					)
					(width 0)
					(fill yes)
				)
			)
		)
	)
	(footprint ""
		(layer "F.Cu")
		(at 172.681138 -96.310704 90)
		(property "Reference" "U4C2"
			(at -2.076704 5.272532 90)
			(unlocked yes)
			(layer "F.SilkS")
			(effects
				(font
					(size 0.7874 0.5842)
					(thickness 0.1524)
				)
				(justify left)
			)
		)
		(property "Value" ""
			(at 0 0 90)
			(layer "F.Fab")
			(effects
				(font
					(size 1.27 1.27)
				)
			)
		)
		(duplicate_pad_numbers_are_jumpers no)
		(fp_line
			(start 4.4323 -0.64008)
			(end 4.4323 4.52628)
			(stroke
				(width 0.1524)
				(type default)
			)
			(layer "F.SilkS")
		)
		(fp_line
			(start 2.667 -0.64008)
			(end 2.667 0.49022)
			(stroke
				(width 0.1524)
				(type default)
			)
			(layer "F.SilkS")
		)
		(fp_line
			(start 1.5367 -0.64008)
			(end 4.4323 -0.64008)
			(stroke
				(width 0.1524)
				(type default)
			)
			(layer "F.SilkS")
		)
		(fp_line
			(start 3.302 0.49022)
			(end 3.302 -0.64008)
			(stroke
				(width 0.1524)
				(type default)
			)
			(layer "F.SilkS")
		)
		(fp_line
			(start 2.667 0.49022)
			(end 3.302 0.49022)
			(stroke
				(width 0.1524)
				(type default)
			)
			(layer "F.SilkS")
		)
		(fp_line
			(start 4.4323 4.52628)
			(end 1.5367 4.52628)
			(stroke
				(width 0.1524)
				(type default)
			)
			(layer "F.SilkS")
		)
		(fp_line
			(start 1.5367 4.52628)
			(end 1.5367 -0.64008)
			(stroke
				(width 0.1524)
				(type default)
			)
			(layer "F.SilkS")
		)
		(fp_circle
			(center -1.612138 -0.684784)
			(end -1.612138 -0.557784)
			(stroke
				(width 0.254)
				(type default)
			)
			(fill no)
			(layer "F.SilkS")
		)
		(fp_poly
			(pts
				(xy 0.7366 4.54152) (xy 0.7366 -0.64008) (xy 4.7244 -0.64008) (xy 5.2324 -0.64008) (xy 5.2324 4.54152)
				(xy 4.7244 4.54152)
			)
			(stroke
				(width 0)
				(type default)
			)
			(fill no)
			(layer "F.CrtYd")
		)
		(fp_line
			(start 5.2324 -0.64008)
			(end 5.2324 4.54152)
			(stroke
				(width 0.1)
				(type default)
			)
			(layer "F.Fab")
		)
		(fp_line
			(start 2.667 -0.64008)
			(end 2.667 0.49022)
			(stroke
				(width 0.1)
				(type default)
			)
			(layer "F.Fab")
		)
		(fp_line
			(start 0.7366 -0.64008)
			(end 5.2324 -0.64008)
			(stroke
				(width 0.1)
				(type default)
			)
			(layer "F.Fab")
		)
		(fp_line
			(start 3.302 0.49022)
			(end 3.302 -0.64008)
			(stroke
				(width 0.1)
				(type default)
			)
			(layer "F.Fab")
		)
		(fp_line
			(start 2.667 0.49022)
			(end 3.302 0.49022)
			(stroke
				(width 0.1)
				(type default)
			)
			(layer "F.Fab")
		)
		(fp_line
			(start 5.2324 4.54152)
			(end 0.7366 4.54152)
			(stroke
				(width 0.1)
				(type default)
			)
			(layer "F.Fab")
		)
		(fp_line
			(start 0.7366 4.54152)
			(end 0.7366 -0.64008)
			(stroke
				(width 0.1)
				(type default)
			)
			(layer "F.Fab")
		)
		(fp_circle
			(center -1.612138 -0.684784)
			(end -1.612138 -0.557784)
			(stroke
				(width 0.635)
				(type default)
			)
			(fill no)
			(layer "F.Fab")
		)
		(pad "1" smd rect
			(at 0 0 90)
			(size 2.159 0.381)
			(layers "F.Cu" "F.Mask" "F.Paste")
			(net "PU_GTL2014_2_DIR")
		)
		(pad "2" smd rect
			(at 0 0.65024 90)
			(size 2.159 0.381)
			(layers "F.Cu" "F.Mask" "F.Paste")
			(net "PWRGD_CPU1_DRAMPWROK_KLM_G")
		)
		(pad "3" smd rect
			(at 0 1.30048 90)
			(size 2.159 0.381)
			(layers "F.Cu" "F.Mask" "F.Paste")
			(net "PWRGD_CPU1_DRAMPWROK_GHJ_G")
		)
		(pad "4" smd rect
			(at 0 1.95072 90)
			(size 2.159 0.381)
			(layers "F.Cu" "F.Mask" "F.Paste")
			(net "PD_GTL2014_2_VREF")
		)
		(pad "5" smd rect
			(at 0 2.60096 90)
			(size 2.159 0.381)
			(layers "F.Cu" "F.Mask" "F.Paste")
			(net "RST_CPU1_G_N")
		)
		(pad "6" smd rect
			(at 0 3.2512 90)
			(size 2.159 0.381)
			(layers "F.Cu" "F.Mask" "F.Paste")
			(net "PWRGD_CPU1_G")
		)
		(pad "7" smd rect
			(at 0 3.90144 90)
			(size 2.159 0.381)
			(layers "F.Cu" "F.Mask" "F.Paste")
			(net "GND")
		)
		(pad "8" smd rect
			(at 5.969 3.90144 90)
			(size 2.159 0.381)
			(layers "F.Cu" "F.Mask" "F.Paste")
			(net "GND")
		)
		(pad "9" smd rect
			(at 5.969 3.2512 90)
			(size 2.159 0.381)
			(layers "F.Cu" "F.Mask" "F.Paste")
			(net "PWRGD_CPU1_LVC3")
		)
		(pad "10" smd rect
			(at 5.969 2.60096 90)
			(size 2.159 0.381)
			(layers "F.Cu" "F.Mask" "F.Paste")
			(net "RST_CPU1_LVC3_N")
		)
		(pad "11" smd rect
			(at 5.969 1.95072 90)
			(size 2.159 0.381)
			(layers "F.Cu" "F.Mask" "F.Paste")
			(net "GND")
		)
		(pad "12" smd rect
			(at 5.969 1.30048 90)
			(size 2.159 0.381)
			(layers "F.Cu" "F.Mask" "F.Paste")
			(net "PWRGD_DRAMPWRGD")
		)
		(pad "13" smd rect
			(at 5.969 0.65024 90)
			(size 2.159 0.381)
			(layers "F.Cu" "F.Mask" "F.Paste")
			(net "PWRGD_DRAMPWRGD")
		)
		(pad "14" smd rect
			(at 5.969 0 90)
			(size 2.159 0.381)
			(layers "F.Cu" "F.Mask" "F.Paste")
			(net "P3V3_STBY")
		)
	)
	(footprint ""
		(layer "F.Cu")
		(at 12.7127 -5.197856 -90)
		(property "Reference" "R1G6"
			(at -0.8382 -0.67818 270)
			(unlocked yes)
			(layer "F.SilkS")
			(effects
				(font
					(size 0.4064 0.254)
					(thickness 0.1524)
				)
				(justify left)
			)
		)
		(property "Value" ""
			(at 0 0 270)
			(layer "F.Fab")
			(effects
				(font
					(size 1.27 1.27)
				)
			)
		)
		(duplicate_pad_numbers_are_jumpers no)
		(fp_poly
			(pts
				(xy -0.2794 -0.1016) (xy 0.2794 -0.1016) (xy 0.2794 0.9906) (xy -0.2794 0.9906)
			)
			(stroke
				(width 0)
				(type default)
			)
			(fill no)
			(layer "F.CrtYd")
		)
		(fp_line
			(start -0.2794 0.9906)
			(end 0.2794 0.9906)
			(stroke
				(width 0.1)
				(type default)
			)
			(layer "F.Fab")
		)
		(fp_line
			(start 0.2794 0.9906)
			(end 0.2794 -0.1016)
			(stroke
				(width 0.1)
				(type default)
			)
			(layer "F.Fab")
		)
		(fp_line
			(start -0.2794 -0.1016)
			(end -0.2794 0.9906)
			(stroke
				(width 0.1)
				(type default)
			)
			(layer "F.Fab")
		)
		(fp_line
			(start 0.2794 -0.1016)
			(end -0.2794 -0.1016)
			(stroke
				(width 0.1)
				(type default)
			)
			(layer "F.Fab")
		)
		(pad "1" smd rect
			(at 0 0 270)
			(size 0.508 0.508)
			(layers "F.Cu" "F.Mask" "F.Paste")
			(net "P3V3_STBY")
		)
		(pad "2" smd rect
			(at 0 0.889 270)
			(size 0.508 0.508)
			(layers "F.Cu" "F.Mask" "F.Paste")
			(net "PWRGD_PVDDQ_GHJ")
		)
		(zone
			(layer "F.Cu")
			(hatch none 0.5)
			(connect_pads
				(clearance 0)
			)
			(min_thickness 0.25)
			(keepout
				(tracks not_allowed)
				(vias allowed)
				(pads allowed)
				(copperpour not_allowed)
				(footprints allowed)
			)
			(placement
				(enabled no)
				(sheetname "")
			)
			(fill
				(thermal_gap 0.5)
				(thermal_bridge_width 0.5)
				(island_removal_mode 0)
			)
			(polygon
				(pts
					(xy 12.0777 -5.451856) (xy 12.0777 -4.943856) (xy 12.4587 -4.943856) (xy 12.4587 -5.451856)
				)
			)
		)
		(zone
			(layer "F.Cu")
			(hatch none 0.5)
			(connect_pads
				(clearance 0)
			)
			(min_thickness 0.25)
			(keepout
				(tracks allowed)
				(vias not_allowed)
				(pads allowed)
				(copperpour not_allowed)
				(footprints allowed)
			)
			(placement
				(enabled no)
				(sheetname "")
			)
			(fill
				(thermal_gap 0.5)
				(thermal_bridge_width 0.5)
				(island_removal_mode 0)
			)
			(polygon
				(pts
					(xy 12.4587 -5.451856) (xy 12.4587 -4.943856) (xy 12.0777 -4.943856) (xy 12.0777 -5.451856)
				)
			)
		)
	)
)
